(kicad_pcb
	(version 20241229)
	(generator "pcbnew")
	(generator_version "9.0")
	(general
		(thickness 1.6)
		(legacy_teardrops no)
	)
	(paper "A4")
	(title_block
		(title "GMSL Deserializer")
		(date "2025-10-09")
		(rev "1.0.4")
		(company "Antmicro Ltd")
		(comment 1 "www.antmicro.com")
		(comment 9 "footprints 175-180 of 235")
	)
	(layers
		(0 "F.Cu" signal)
		(4 "In1.Cu" power)
		(6 "In2.Cu" power)
		(2 "B.Cu" signal)
		(9 "F.Adhes" user "F.Adhesive")
		(11 "B.Adhes" user "B.Adhesive")
		(13 "F.Paste" user)
		(15 "B.Paste" user)
		(5 "F.SilkS" user "F.Silkscreen")
		(7 "B.SilkS" user "B.Silkscreen")
		(1 "F.Mask" user)
		(3 "B.Mask" user)
		(17 "Dwgs.User" user "User.Drawings")
		(19 "Cmts.User" user "User.Comments")
		(21 "Eco1.User" user "User.Eco1")
		(23 "Eco2.User" user "User.Eco2")
		(25 "Edge.Cuts" user)
		(27 "Margin" user)
		(31 "F.CrtYd" user "F.Courtyard")
		(29 "B.CrtYd" user "B.Courtyard")
		(35 "F.Fab" user)
		(33 "B.Fab" user)
	)
	(footprint "antmicro-footprints:LED_0603_1608Metric_G"
		(layer "F.Cu")
		(at 153.924 96.11 -90)
		(descr "LED SMD 0603 Green")
		(tags "LED SMD 0603 Green")
		(property "Reference" "D15"
			(at -0.86 35.507333 0)
			(layer "F.SilkS")
			(effects
				(font
					(size 0.7 0.7)
					(thickness 0.15)
				)
				(justify right bottom)
			)
		)
		(property "Value" "LED_G_0603_LTST-C190GKT"
			(at -0.001 1.599 90)
			(layer "F.Fab")
			(effects
				(font
					(size 0.7 0.7)
					(thickness 0.15)
				)
				(justify right bottom)
			)
		)
		(property "Datasheet" "https://media.digikey.com/pdf/Data%20Sheets/Lite-On%20PDFs/LTST-C190GKT.pdf"
			(at 0 0 270)
			(layer "F.Fab")
			(hide yes)
			(effects
				(font
					(size 1.27 1.27)
					(thickness 0.15)
				)
			)
		)
		(property "Description" "LED, Green, SMD, 0603, 20 mA, 2.1 V, 569 nm"
			(at 0 0 270)
			(layer "F.Fab")
			(hide yes)
			(effects
				(font
					(size 1.27 1.27)
					(thickness 0.15)
				)
			)
		)
		(property "Author" "Antmicro"
			(at 57.814 250.034 0)
			(layer "F.Fab")
			(hide yes)
			(effects
				(font
					(size 1 1)
					(thickness 0.15)
				)
			)
		)
		(property "Color" "Green"
			(at 57.814 250.034 0)
			(layer "F.Fab")
			(hide yes)
			(effects
				(font
					(size 1 1)
					(thickness 0.15)
				)
			)
		)
		(property "License" "Apache-2.0"
			(at 57.814 250.034 0)
			(layer "F.Fab")
			(hide yes)
			(effects
				(font
					(size 1 1)
					(thickness 0.15)
				)
			)
		)
		(property "MPN" "LTST-C190GKT"
			(at 57.814 250.034 0)
			(layer "F.Fab")
			(hide yes)
			(effects
				(font
					(size 1 1)
					(thickness 0.15)
				)
			)
		)
		(property "Manufacturer" "Lite-On"
			(at 57.814 250.034 0)
			(layer "F.Fab")
			(hide yes)
			(effects
				(font
					(size 1 1)
					(thickness 0.15)
				)
			)
		)
		(property "VSD_class" "LED"
			(at 57.814 250.034 0)
			(layer "F.Fab")
			(hide yes)
			(effects
				(font
					(size 1 1)
					(thickness 0.15)
				)
			)
		)
		(sheetname "/Power/")
		(sheetfile "power.kicad_sch")
		(attr smd)
		(fp_line
			(start 0.22 0.35)
			(end -0.22 0.35)
			(stroke
				(width 0.15)
				(type solid)
			)
			(layer "F.SilkS")
		)
		(fp_line
			(start -0.094672 0.201008)
			(end -0.094672 -0.198992)
			(stroke
				(width 0.1)
				(type solid)
			)
			(layer "F.SilkS")
		)
		(fp_line
			(start 0.105328 0.201008)
			(end -0.094672 0.001008)
			(stroke
				(width 0.1)
				(type solid)
			)
			(layer "F.SilkS")
		)
		(fp_line
			(start 0.105328 0.201008)
			(end 0.105328 -0.198992)
			(stroke
				(width 0.1)
				(type solid)
			)
			(layer "F.SilkS")
		)
		(fp_line
			(start -0.094672 0.001008)
			(end -0.24 0.001008)
			(stroke
				(width 0.1)
				(type solid)
			)
			(layer "F.SilkS")
		)
		(fp_line
			(start -0.094672 0.001008)
			(end 0.105328 -0.198992)
			(stroke
				(width 0.1)
				(type solid)
			)
			(layer "F.SilkS")
		)
		(fp_line
			(start 0.105328 0.001008)
			(end 0.24 0.001)
			(stroke
				(width 0.1)
				(type solid)
			)
			(layer "F.SilkS")
		)
		(fp_line
			(start -1.18 -0.319)
			(end -1.18 0.321)
			(stroke
				(width 0.15)
				(type solid)
			)
			(layer "F.SilkS")
		)
		(fp_line
			(start 0.22 -0.35)
			(end -0.22 -0.35)
			(stroke
				(width 0.15)
				(type solid)
			)
			(layer "F.SilkS")
		)
		(fp_rect
			(start 1.25 0.65)
			(end -1.25 -0.65)
			(stroke
				(width 0.05)
				(type solid)
			)
			(fill no)
			(layer "F.CrtYd")
		)
		(fp_line
			(start -0.199 0.2)
			(end -0.199 0.1)
			(stroke
				(width 0.15)
				(type solid)
			)
			(layer "F.Fab")
		)
		(fp_line
			(start 0.201 0.2)
			(end 0.201 0)
			(stroke
				(width 0.15)
				(type solid)
			)
			(layer "F.Fab")
		)
		(fp_line
			(start -0.199 0)
			(end -0.597 0)
			(stroke
				(width 0.15)
				(type solid)
			)
			(layer "F.Fab")
		)
		(fp_line
			(start -0.101 0)
			(end 0.201 0.2)
			(stroke
				(width 0.15)
				(type solid)
			)
			(layer "F.Fab")
		)
		(fp_line
			(start 0.201 0)
			(end 0.201 -0.202)
			(stroke
				(width 0.15)
				(type solid)
			)
			(layer "F.Fab")
		)
		(fp_line
			(start 0.599 0)
			(end 0.201 0)
			(stroke
				(width 0.15)
				(type solid)
			)
			(layer "F.Fab")
		)
		(fp_line
			(start -0.199 -0.202)
			(end -0.199 0.1)
			(stroke
				(width 0.15)
				(type solid)
			)
			(layer "F.Fab")
		)
		(fp_line
			(start 0.201 -0.202)
			(end -0.101 0)
			(stroke
				(width 0.15)
				(type solid)
			)
			(layer "F.Fab")
		)
		(fp_rect
			(start 0.848 0.4)
			(end -0.85 -0.402)
			(stroke
				(width 0.15)
				(type solid)
			)
			(fill no)
			(layer "F.Fab")
		)
		(pad "1" smd roundrect
			(at -0.7 0 90)
			(size 0.8 1)
			(layers "F.Cu" "F.Mask" "F.Paste")
			(roundrect_rratio 0.2)
			(net 112 "Net-(D15-C)")
			(pinfunction "C")
			(pintype "passive")
		)
		(pad "2" smd roundrect
			(at 0.7 0 90)
			(size 0.8 1)
			(layers "F.Cu" "F.Mask" "F.Paste")
			(roundrect_rratio 0.2)
			(net 118 "/Connectors/DC_IN")
			(pinfunction "A")
			(pintype "passive")
		)
	)
	(footprint "antmicro-footprints:R_0402_1005Metric"
		(layer "F.Cu")
		(at 177.804 54.609 180)
		(descr "Resistor SMD 0402")
		(tags "resistor SMD 0402")
		(property "Reference" "R15"
			(at -2.846 -0.741 0)
			(layer "F.SilkS")
			(effects
				(font
					(size 0.7 0.7)
					(thickness 0.15)
				)
				(justify right bottom)
			)
		)
		(property "Value" "R_100R_0402"
			(at -1.011843 1.772047 0)
			(layer "F.Fab")
			(effects
				(font
					(size 0.7 0.7)
					(thickness 0.15)
				)
				(justify right bottom)
			)
		)
		(property "Datasheet" "https://www.bourns.com/docs/product-datasheets/cr.pdf"
			(at 0 0 180)
			(layer "F.Fab")
			(hide yes)
			(effects
				(font
					(size 1.27 1.27)
					(thickness 0.15)
				)
			)
		)
		(property "Description" "SMD Chip Resistor, 100 ohm, ± 1%, 62.5 mW, 0402 [1005 Metric], Thick Film, General Purpose"
			(at 0 0 180)
			(layer "F.Fab")
			(hide yes)
			(effects
				(font
					(size 1.27 1.27)
					(thickness 0.15)
				)
			)
		)
		(property "Author" "Antmicro"
			(at 355.608 109.218 0)
			(layer "F.Fab")
			(hide yes)
			(effects
				(font
					(size 1 1)
					(thickness 0.15)
				)
			)
		)
		(property "License" "Apache-2.0"
			(at 355.608 109.218 0)
			(layer "F.Fab")
			(hide yes)
			(effects
				(font
					(size 1 1)
					(thickness 0.15)
				)
			)
		)
		(property "MPN" "CR0402-FX-1000GLF"
			(at 355.608 109.218 0)
			(layer "F.Fab")
			(hide yes)
			(effects
				(font
					(size 1 1)
					(thickness 0.15)
				)
			)
		)
		(property "Manufacturer" "Bourns"
			(at 355.608 109.218 0)
			(layer "F.Fab")
			(hide yes)
			(effects
				(font
					(size 1 1)
					(thickness 0.15)
				)
			)
		)
		(property "Tolerance" "1%"
			(at 355.608 109.218 0)
			(layer "F.Fab")
			(hide yes)
			(effects
				(font
					(size 1 1)
					(thickness 0.15)
				)
			)
		)
		(property "Val" "100R"
			(at 355.608 109.218 0)
			(layer "F.Fab")
			(hide yes)
			(effects
				(font
					(size 1 1)
					(thickness 0.15)
				)
			)
		)
		(sheetname "/Power/")
		(sheetfile "power.kicad_sch")
		(attr smd)
		(fp_rect
			(start -0.925 -0.47)
			(end 0.925 0.47)
			(stroke
				(width 0.05)
				(type default)
			)
			(fill no)
			(layer "F.CrtYd")
		)
		(fp_rect
			(start -0.5 -0.25)
			(end 0.5 0.25)
			(stroke
				(width 0.15)
				(type solid)
			)
			(fill no)
			(layer "F.Fab")
		)
		(pad "1" smd roundrect
			(at -0.48 0 180)
			(size 0.59 0.64)
			(layers "F.Cu" "F.Mask" "F.Paste")
			(roundrect_rratio 0.25)
			(net 126 "Net-(Q1-G)")
			(pintype "passive")
		)
		(pad "2" smd roundrect
			(at 0.48 0 180)
			(size 0.59 0.64)
			(layers "F.Cu" "F.Mask" "F.Paste")
			(roundrect_rratio 0.25)
			(net 118 "/Connectors/DC_IN")
			(pintype "passive")
		)
	)
	(footprint "antmicro-footprints:TP_SMD_0.75mm"
		(layer "F.Cu")
		(at 144.78 97.89)
		(property "Reference" "TP13"
			(at 0 -0.6 0)
			(layer "F.SilkS")
			(hide yes)
			(effects
				(font
					(size 0.7 0.7)
					(thickness 0.15)
				)
				(justify left bottom)
			)
		)
		(property "Value" "TP_0.75mm_SMD"
			(at 0 1.2 0)
			(layer "F.Fab")
			(effects
				(font
					(size 0.7 0.7)
					(thickness 0.15)
				)
				(justify left bottom)
			)
		)
		(property "Description" "SMT test point"
			(at 0 0 0)
			(layer "F.Fab")
			(hide yes)
			(effects
				(font
					(size 1.27 1.27)
					(thickness 0.15)
				)
			)
		)
		(property "Author" "Antmicro"
			(at 0 0 0)
			(layer "F.Fab")
			(hide yes)
			(effects
				(font
					(size 1 1)
					(thickness 0.15)
				)
			)
		)
		(property "License" "Apache-2.0"
			(at 0 0 0)
			(layer "F.Fab")
			(hide yes)
			(effects
				(font
					(size 1 1)
					(thickness 0.15)
				)
			)
		)
		(property "MPN" ""
			(at 0 0 0)
			(layer "F.Fab")
			(hide yes)
			(effects
				(font
					(size 1 1)
					(thickness 0.15)
				)
			)
		)
		(property "Manufacturer" ""
			(at 0 0 0)
			(layer "F.Fab")
			(hide yes)
			(effects
				(font
					(size 1 1)
					(thickness 0.15)
				)
			)
		)
		(sheetname "/Power/")
		(sheetfile "power.kicad_sch")
		(fp_circle
			(center 0 0)
			(end 0.475 0)
			(stroke
				(width 0.05)
				(type default)
			)
			(fill no)
			(layer "F.CrtYd")
		)
		(pad "1" smd circle
			(at 0 0)
			(size 0.75 0.75)
			(layers "F.Cu" "F.Mask")
			(net 10 "/Power/OUT_1V8")
			(pinfunction "1")
			(pintype "passive")
		)
	)
	(footprint "antmicro-footprints:TP_SMD_0.75mm"
		(layer "B.Cu")
		(at 157.25 76.05 180)
		(property "Reference" "TP25"
			(at 0 0.6 0)
			(layer "B.SilkS")
			(hide yes)
			(effects
				(font
					(size 0.7 0.7)
					(thickness 0.15)
				)
				(justify left bottom mirror)
			)
		)
		(property "Value" "TP_0.75mm_SMD"
			(at 0 -1.2 0)
			(layer "B.Fab")
			(effects
				(font
					(size 0.7 0.7)
					(thickness 0.15)
				)
				(justify left bottom mirror)
			)
		)
		(property "Description" "SMT test point"
			(at 0 0 0)
			(layer "B.Fab")
			(hide yes)
			(effects
				(font
					(size 1.27 1.27)
					(thickness 0.15)
				)
				(justify mirror)
			)
		)
		(property "MPN" ""
			(at 0 0 0)
			(unlocked yes)
			(layer "B.Fab")
			(hide yes)
			(effects
				(font
					(size 1 1)
					(thickness 0.15)
				)
				(justify mirror)
			)
		)
		(property "Manufacturer" ""
			(at 0 0 0)
			(unlocked yes)
			(layer "B.Fab")
			(hide yes)
			(effects
				(font
					(size 1 1)
					(thickness 0.15)
				)
				(justify mirror)
			)
		)
		(property "Author" "Antmicro"
			(at 0 0 0)
			(unlocked yes)
			(layer "B.Fab")
			(hide yes)
			(effects
				(font
					(size 1 1)
					(thickness 0.15)
				)
				(justify mirror)
			)
		)
		(property "License" "Apache-2.0"
			(at 0 0 0)
			(unlocked yes)
			(layer "B.Fab")
			(hide yes)
			(effects
				(font
					(size 1 1)
					(thickness 0.15)
				)
				(justify mirror)
			)
		)
		(sheetname "/Connectors/")
		(sheetfile "connectors.kicad_sch")
		(attr exclude_from_pos_files)
		(fp_circle
			(center 0 0)
			(end 0.475 0)
			(stroke
				(width 0.05)
				(type default)
			)
			(fill no)
			(layer "B.CrtYd")
		)
		(fp_text user "Author: Antmicro"
			(at -0.4 -3.901 0)
			(layer "B.Fab")
			(effects
				(font
					(size 0.7 0.7)
					(thickness 0.15)
				)
				(justify left bottom mirror)
			)
		)
		(fp_text user "${REFERENCE}"
			(at -0.4 -2.7 0)
			(layer "B.Fab")
			(effects
				(font
					(size 0.7 0.7)
					(thickness 0.15)
				)
				(justify left bottom mirror)
			)
		)
		(fp_text user "License: Apache-2.0"
			(at -0.4 -5.101 0)
			(layer "B.Fab")
			(effects
				(font
					(size 0.7 0.7)
					(thickness 0.15)
				)
				(justify left bottom mirror)
			)
		)
		(pad "1" smd circle
			(at 0 0 180)
			(size 0.75 0.75)
			(layers "B.Cu" "B.Mask")
			(net 121 "/Connectors/SCL")
			(pinfunction "1")
			(pintype "passive")
		)
	)
	(footprint "antmicro-footprints:C_0402_1005Metric"
		(layer "B.Cu")
		(at 142.588 77.056 -45)
		(descr "Capacitor SMD 0402")
		(tags "capacitor SMD 0402")
		(property "Reference" "C39"
			(at -1.52271 0.22729 315)
			(unlocked yes)
			(layer "B.SilkS")
			(effects
				(font
					(size 0.7 0.7)
					(thickness 0.15)
				)
				(justify left bottom mirror)
			)
		)
		(property "Value" "C_100n_0402"
			(at -1.022927 -2.155213 135)
			(layer "B.Fab")
			(effects
				(font
					(size 0.7 0.7)
					(thickness 0.15)
				)
				(justify left bottom mirror)
			)
		)
		(property "Datasheet" "https://www.murata.com/products/productdetail?partno=GRM155R61H104KE14%23"
			(at 0 0 315)
			(layer "F.Fab")
			(hide yes)
			(effects
				(font
					(size 1.27 1.27)
					(thickness 0.15)
				)
			)
		)
		(property "Description" "SMD Multilayer Ceramic Capacitor, 0.1 µF, 50 V, 0402 [1005 Metric], ± 10%, X5R, GRM Series"
			(at 0 0 315)
			(layer "F.Fab")
			(hide yes)
			(effects
				(font
					(size 1.27 1.27)
					(thickness 0.15)
				)
			)
		)
		(property "Author" "Antmicro"
			(at -12.790036 123.554121 0)
			(layer "B.Fab")
			(hide yes)
			(effects
				(font
					(size 1 1)
					(thickness 0.15)
				)
				(justify mirror)
			)
		)
		(property "Dielectric" "X5R"
			(at -12.790036 123.554121 0)
			(layer "B.Fab")
			(hide yes)
			(effects
				(font
					(size 1 1)
					(thickness 0.15)
				)
				(justify mirror)
			)
		)
		(property "License" "Apache-2.0"
			(at -12.790036 123.554121 0)
			(layer "B.Fab")
			(hide yes)
			(effects
				(font
					(size 1 1)
					(thickness 0.15)
				)
				(justify mirror)
			)
		)
		(property "MPN" "GRM155R61H104KE14D"
			(at -12.790036 123.554121 0)
			(layer "B.Fab")
			(hide yes)
			(effects
				(font
					(size 1 1)
					(thickness 0.15)
				)
				(justify mirror)
			)
		)
		(property "Manufacturer" "Murata"
			(at -12.790036 123.554121 0)
			(layer "B.Fab")
			(hide yes)
			(effects
				(font
					(size 1 1)
					(thickness 0.15)
				)
				(justify mirror)
			)
		)
		(property "Val" "100n"
			(at -12.790036 123.554121 0)
			(layer "B.Fab")
			(hide yes)
			(effects
				(font
					(size 1 1)
					(thickness 0.15)
				)
				(justify mirror)
			)
		)
		(property "Voltage" "50V"
			(at -12.790036 123.554121 0)
			(layer "B.Fab")
			(hide yes)
			(effects
				(font
					(size 1 1)
					(thickness 0.15)
				)
				(justify mirror)
			)
		)
		(sheetname "/Deserializer/")
		(sheetfile "deserializer.kicad_sch")
		(attr smd)
		(fp_poly
			(pts
				(xy -0.925 0.47) (xy 0.925 0.47) (xy 0.925 -0.47) (xy -0.925 -0.47)
			)
			(stroke
				(width 0.05)
				(type default)
			)
			(fill no)
			(layer "B.CrtYd")
		)
		(fp_line
			(start -0.494 0.25)
			(end -0.494 -0.248)
			(stroke
				(width 0.15)
				(type solid)
			)
			(layer "B.Fab")
		)
		(fp_line
			(start -0.494 -0.248)
			(end 0.504 -0.248)
			(stroke
				(width 0.15)
				(type solid)
			)
			(layer "B.Fab")
		)
		(fp_line
			(start 0.504 0.25)
			(end -0.494 0.25)
			(stroke
				(width 0.15)
				(type solid)
			)
			(layer "B.Fab")
		)
		(fp_line
			(start 0.504 -0.248)
			(end 0.504 0.25)
			(stroke
				(width 0.15)
				(type solid)
			)
			(layer "B.Fab")
		)
		(pad "1" smd roundrect
			(at -0.48 0 315)
			(size 0.59 0.64)
			(layers "B.Cu" "B.Mask" "B.Paste")
			(roundrect_rratio 0.25)
			(net 1 "GND")
			(pintype "passive")
		)
		(pad "2" smd roundrect
			(at 0.48 0 315)
			(size 0.59 0.64)
			(layers "B.Cu" "B.Mask" "B.Paste")
			(roundrect_rratio 0.25)
			(net 26 "/Deserializer/VDD_1.8V")
			(pintype "passive")
		)
	)
	(footprint "antmicro-footprints:R_0402_1005Metric"
		(layer "B.Cu")
		(at 146.321605 96.355897 -90)
		(descr "Resistor SMD 0402")
		(tags "resistor SMD 0402")
		(property "Reference" "R80"
			(at -5.724873 -0.425736 90)
			(layer "B.SilkS")
			(effects
				(font
					(size 0.7 0.7)
					(thickness 0.15)
				)
				(justify right bottom mirror)
			)
		)
		(property "Value" "R_470R_0402"
			(at -1.011843 -1.772046 90)
			(layer "B.Fab")
			(effects
				(font
					(size 0.7 0.7)
					(thickness 0.15)
				)
				(justify left bottom mirror)
			)
		)
		(property "Datasheet" "https://www.bourns.com/docs/product-datasheets/cr.pdf"
			(at 0 0 90)
			(layer "F.Fab")
			(hide yes)
			(effects
				(font
					(size 1.27 1.27)
					(thickness 0.15)
				)
			)
		)
		(property "Description" "SMD Chip Resistor, 470 ohm, ± 1%, 62.5 mW, 0402 [1005 Metric], Thick Film, General Purpose"
			(at 0 0 90)
			(layer "F.Fab")
			(hide yes)
			(effects
				(font
					(size 1.27 1.27)
					(thickness 0.15)
				)
			)
		)
		(property "Author" "Antmicro"
			(at -24.712942 131.716501 135)
			(layer "B.Fab")
			(hide yes)
			(effects
				(font
					(size 1 1)
					(thickness 0.15)
				)
				(justify mirror)
			)
		)
		(property "License" "Apache-2.0"
			(at -24.712942 131.716501 135)
			(layer "B.Fab")
			(hide yes)
			(effects
				(font
					(size 1 1)
					(thickness 0.15)
				)
				(justify mirror)
			)
		)
		(property "MPN" "CR0402-FX-4700GLF"
			(at -24.712942 131.716501 135)
			(layer "B.Fab")
			(hide yes)
			(effects
				(font
					(size 1 1)
					(thickness 0.15)
				)
				(justify mirror)
			)
		)
		(property "Manufacturer" "Bourns"
			(at -24.712942 131.716501 135)
			(layer "B.Fab")
			(hide yes)
			(effects
				(font
					(size 1 1)
					(thickness 0.15)
				)
				(justify mirror)
			)
		)
		(property "Tolerance" "1%"
			(at -24.712942 131.716501 135)
			(layer "B.Fab")
			(hide yes)
			(effects
				(font
					(size 1 1)
					(thickness 0.15)
				)
				(justify mirror)
			)
		)
		(property "Val" "470R"
			(at -24.712942 131.716501 135)
			(layer "B.Fab")
			(hide yes)
			(effects
				(font
					(size 1 1)
					(thickness 0.15)
				)
				(justify mirror)
			)
		)
		(sheetname "/Power/")
		(sheetfile "power.kicad_sch")
		(attr smd)
		(fp_poly
			(pts
				(xy -0.925 0.47) (xy 0.925 0.47) (xy 0.925 -0.47) (xy -0.925 -0.47)
			)
			(stroke
				(width 0.05)
				(type default)
			)
			(fill no)
			(layer "B.CrtYd")
		)
		(fp_poly
			(pts
				(xy -0.5 0.25) (xy 0.5 0.25) (xy 0.5 -0.25) (xy -0.5 -0.25)
			)
			(stroke
				(width 0.15)
				(type solid)
			)
			(fill no)
			(layer "B.Fab")
		)
		(pad "1" smd roundrect
			(at -0.48 0 270)
			(size 0.59 0.64)
			(layers "B.Cu" "B.Mask" "B.Paste")
			(roundrect_rratio 0.25)
			(net 144 "Net-(D19-A)")
			(pintype "passive")
		)
		(pad "2" smd roundrect
			(at 0.48 0 270)
			(size 0.59 0.64)
			(layers "B.Cu" "B.Mask" "B.Paste")
			(roundrect_rratio 0.25)
			(net 5 "+5V")
			(pintype "passive")
		)
	)
)
